# S9S_MB_2U (Grand Teton) — schematic netlist excerpt (pin names and nets, part order shuffled) for the footprints in the layout excerpt that follows; sources: Cadence DE-HDL packaged netlist, KiCad conversion of 03242023_DA0F0TMBIJ0_F0T_Motherboard_J_brd_V01_OCP.brd

PC1203_P1_4  Q_CAP  100NF 50V 10% X7R  pkg C0402  page 290 : A = PVCCFA_EHV_FIVRA_CPU1 ; B = GND
R4105  Q_RES  10K 1% CHIP  pkg 0402LF  page 184 : A = PD_GPP_M_15 ; B = GND

(kicad_pcb
	(version 20260206)
	(generator "pcbnew")
	(generator_version "10.0")
	(general
		(thickness 1.6)
		(legacy_teardrops no)
	)
	(paper "A4")
	(title_block
		(title "03242023_DA0F0TMBIJ0_F0T_Motherboard_J_brd_V01_OCP.brd")
		(comment 1 "Grand Teton / footprints 4470-4471 of 6105")
	)
	(layers
		(0 "F.Cu" signal "TOP")
		(4 "In1.Cu" signal "GND")
		(6 "In2.Cu" signal "IN1")
		(8 "In3.Cu" signal "GND1")
		(10 "In4.Cu" signal "IN2")
		(12 "In5.Cu" signal "GND2")
		(14 "In6.Cu" signal "IN3")
		(16 "In7.Cu" signal "GND3")
		(18 "In8.Cu" signal "VCC")
		(20 "In9.Cu" signal "VCC1")
		(22 "In10.Cu" signal "GND4")
		(24 "In11.Cu" signal "IN4")
		(26 "In12.Cu" signal "GND5")
		(28 "In13.Cu" signal "IN5")
		(30 "In14.Cu" signal "GND6")
		(32 "In15.Cu" signal "IN6")
		(34 "In16.Cu" signal "GND7")
		(2 "B.Cu" signal "BOTTOM")
		(9 "F.Adhes" user "F.Adhesive")
		(11 "B.Adhes" user "B.Adhesive")
		(13 "F.Paste" user "Package Geometry/Pastemask Top")
		(15 "B.Paste" user "Package Geometry/Pastemask Bottom")
		(5 "F.SilkS" user "Ref Des/Silkscreen Top")
		(7 "B.SilkS" user "Ref Des/Silkscreen Bottom")
		(1 "F.Mask" user "Board Geometry/Soldermask Top")
		(3 "B.Mask" user "Board Geometry/Soldermask Bottom")
		(17 "Dwgs.User" user "User.Drawings")
		(19 "Cmts.User" user "User.Comments")
		(21 "Eco1.User" user "User.Eco1")
		(23 "Eco2.User" user "User.Eco2")
		(25 "Edge.Cuts" user "Board Geometry/Outline")
		(27 "Margin" user)
		(31 "F.CrtYd" user "Package Geometry/Place Bound Top")
		(29 "B.CrtYd" user "Package Geometry/Place Bound Bottom")
		(35 "F.Fab" user "Ref Des/Assembly Top")
		(33 "B.Fab" user "Ref Des/Assembly Bottom")
	)
	(footprint ""
		(layer "B.Cu")
		(at 311.84088 -54.320948)
		(property "Reference" "R4105"
			(at 0 0 0)
			(layer "B.SilkS")
			(hide yes)
			(effects
				(font
					(size 1.27 1.27)
				)
				(justify mirror)
			)
		)
		(property "Value" ""
			(at 0 0 0)
			(layer "B.Fab")
			(effects
				(font
					(size 1.27 1.27)
				)
				(justify mirror)
			)
		)
		(duplicate_pad_numbers_are_jumpers no)
		(fp_line
			(start -0.7874 -0.4064)
			(end -0.7874 0.4064)
			(stroke
				(width 0.1524)
				(type default)
			)
			(layer "B.SilkS")
		)
		(fp_line
			(start -0.7874 0.4064)
			(end 0.7874 0.4064)
			(stroke
				(width 0.1524)
				(type default)
			)
			(layer "B.SilkS")
		)
		(fp_line
			(start 0.7874 -0.4064)
			(end -0.7874 -0.4064)
			(stroke
				(width 0.1524)
				(type default)
			)
			(layer "B.SilkS")
		)
		(fp_line
			(start 0.7874 0.4064)
			(end 0.7874 -0.4064)
			(stroke
				(width 0.1524)
				(type default)
			)
			(layer "B.SilkS")
		)
		(fp_line
			(start -0.67945 -0.3048)
			(end -0.67945 0.3048)
			(stroke
				(width 0.1)
				(type default)
			)
			(layer "B.Fab")
		)
		(fp_line
			(start -0.67945 0.3048)
			(end -0.120396 0.3048)
			(stroke
				(width 0.1)
				(type default)
			)
			(layer "B.Fab")
		)
		(fp_line
			(start -0.12065 -0.3048)
			(end -0.67945 -0.3048)
			(stroke
				(width 0.1)
				(type default)
			)
			(layer "B.Fab")
		)
		(fp_line
			(start -0.12065 -0.2794)
			(end -0.12065 -0.3048)
			(stroke
				(width 0.1)
				(type default)
			)
			(layer "B.Fab")
		)
		(fp_line
			(start -0.120396 0.2794)
			(end 0.12065 0.2794)
			(stroke
				(width 0.1)
				(type default)
			)
			(layer "B.Fab")
		)
		(fp_line
			(start -0.120396 0.3048)
			(end -0.120396 0.2794)
			(stroke
				(width 0.1)
				(type default)
			)
			(layer "B.Fab")
		)
		(fp_line
			(start 0.12065 -0.305054)
			(end 0.12065 -0.2794)
			(stroke
				(width 0.1)
				(type default)
			)
			(layer "B.Fab")
		)
		(fp_line
			(start 0.12065 -0.2794)
			(end -0.12065 -0.2794)
			(stroke
				(width 0.1)
				(type default)
			)
			(layer "B.Fab")
		)
		(fp_line
			(start 0.12065 0.2794)
			(end 0.12065 0.3048)
			(stroke
				(width 0.1)
				(type default)
			)
			(layer "B.Fab")
		)
		(fp_line
			(start 0.12065 0.3048)
			(end 0.67945 0.3048)
			(stroke
				(width 0.1)
				(type default)
			)
			(layer "B.Fab")
		)
		(fp_line
			(start 0.67945 -0.305054)
			(end 0.12065 -0.305054)
			(stroke
				(width 0.1)
				(type default)
			)
			(layer "B.Fab")
		)
		(fp_line
			(start 0.67945 0.3048)
			(end 0.67945 -0.305054)
			(stroke
				(width 0.1)
				(type default)
			)
			(layer "B.Fab")
		)
		(pad "1" smd circle
			(at 0.40005 0 180)
			(size 0 0)
			(layers "B.Cu" "B.Mask" "B.Paste")
			(net "PD_GPP_M_15")
		)
		(pad "2" smd circle
			(at -0.40005 0 180)
			(size 0 0)
			(layers "B.Cu" "B.Mask" "B.Paste")
			(net "GND")
		)
	)
	(footprint ""
		(layer "B.Cu")
		(at 46.412658 -344.729054 -90)
		(property "Reference" "PC1203_P1_4"
			(at 0 0 90)
			(layer "B.SilkS")
			(hide yes)
			(effects
				(font
					(size 1.27 1.27)
				)
				(justify mirror)
			)
		)
		(property "Value" ""
			(at 0 0 90)
			(layer "B.Fab")
			(effects
				(font
					(size 1.27 1.27)
				)
				(justify mirror)
			)
		)
		(duplicate_pad_numbers_are_jumpers no)
		(fp_line
			(start -0.7874 0.4064)
			(end 0.7874 0.4064)
			(stroke
				(width 0.1524)
				(type default)
			)
			(layer "B.SilkS")
		)
		(fp_line
			(start 0.7874 0.4064)
			(end 0.7874 -0.4064)
			(stroke
				(width 0.1524)
				(type default)
			)
			(layer "B.SilkS")
		)
		(fp_line
			(start -0.7874 -0.4064)
			(end -0.7874 0.4064)
			(stroke
				(width 0.1524)
				(type default)
			)
			(layer "B.SilkS")
		)
		(fp_line
			(start 0.7874 -0.4064)
			(end -0.7874 -0.4064)
			(stroke
				(width 0.1524)
				(type default)
			)
			(layer "B.SilkS")
		)
		(fp_line
			(start -0.67945 0.3048)
			(end -0.120396 0.3048)
			(stroke
				(width 0.1)
				(type default)
			)
			(layer "B.Fab")
		)
		(fp_line
			(start -0.120396 0.3048)
			(end -0.120396 0.2794)
			(stroke
				(width 0.1)
				(type default)
			)
			(layer "B.Fab")
		)
		(fp_line
			(start 0.12065 0.3048)
			(end 0.67945 0.3048)
			(stroke
				(width 0.1)
				(type default)
			)
			(layer "B.Fab")
		)
		(fp_line
			(start 0.67945 0.3048)
			(end 0.67945 -0.305054)
			(stroke
				(width 0.1)
				(type default)
			)
			(layer "B.Fab")
		)
		(fp_line
			(start -0.120396 0.2794)
			(end 0.12065 0.2794)
			(stroke
				(width 0.1)
				(type default)
			)
			(layer "B.Fab")
		)
		(fp_line
			(start 0.12065 0.2794)
			(end 0.12065 0.3048)
			(stroke
				(width 0.1)
				(type default)
			)
			(layer "B.Fab")
		)
		(fp_line
			(start -0.12065 -0.2794)
			(end -0.12065 -0.3048)
			(stroke
				(width 0.1)
				(type default)
			)
			(layer "B.Fab")
		)
		(fp_line
			(start 0.12065 -0.2794)
			(end -0.12065 -0.2794)
			(stroke
				(width 0.1)
				(type default)
			)
			(layer "B.Fab")
		)
		(fp_line
			(start -0.67945 -0.3048)
			(end -0.67945 0.3048)
			(stroke
				(width 0.1)
				(type default)
			)
			(layer "B.Fab")
		)
		(fp_line
			(start -0.12065 -0.3048)
			(end -0.67945 -0.3048)
			(stroke
				(width 0.1)
				(type default)
			)
			(layer "B.Fab")
		)
		(fp_line
			(start 0.12065 -0.305054)
			(end 0.12065 -0.2794)
			(stroke
				(width 0.1)
				(type default)
			)
			(layer "B.Fab")
		)
		(fp_line
			(start 0.67945 -0.305054)
			(end 0.12065 -0.305054)
			(stroke
				(width 0.1)
				(type default)
			)
			(layer "B.Fab")
		)
		(pad "1" smd circle
			(at 0.40005 0 90)
			(size 0 0)
			(layers "B.Cu" "B.Mask" "B.Paste")
			(net "PVCCFA_EHV_FIVRA_CPU1")
		)
		(pad "2" smd circle
			(at -0.40005 0 90)
			(size 0 0)
			(layers "B.Cu" "B.Mask" "B.Paste")
			(net "GND")
		)
	)
)
